(kicad_pcb
	(version 20260206)
	(generator "pcbnew")
	(generator_version "10.0")
	(general
		(thickness 1.59074)
		(legacy_teardrops no)
	)
	(paper "A4")
	(title_block
		(title "osc-sa45 — FAB_SA45_DaughterCard.PcbDoc")
		(comment 1 "Time Appliance Project (Time Card) / footprints 7-13 of 44")
	)
	(layers
		(0 "F.Cu" signal "L01-Top Layer")
		(4 "In1.Cu" signal "L02-Inner Layer")
		(6 "In2.Cu" signal "L03-Inner Layer")
		(2 "B.Cu" signal "L04-Bottom Layer")
		(9 "F.Adhes" user "F.Adhesive")
		(11 "B.Adhes" user "B.Adhesive")
		(13 "F.Paste" user "Top Paste")
		(15 "B.Paste" user "Bottom Paste")
		(5 "F.SilkS" user "Top Overlay")
		(7 "B.SilkS" user "Bottom Overlay")
		(1 "F.Mask" user "Top Solder")
		(3 "B.Mask" user "Bottom Solder")
		(17 "Dwgs.User" user "User.Drawings")
		(19 "Cmts.User" user "User.Comments")
		(21 "Eco1.User" user "User.Eco1")
		(23 "Eco2.User" user "User.Eco2")
		(25 "Edge.Cuts" user)
		(27 "Margin" user)
		(31 "F.CrtYd" user "Top Courtyard")
		(29 "B.CrtYd" user "Bottom Courtyard")
		(35 "F.Fab" user "Top Component Outline")
		(33 "B.Fab" user "Bottom Component Outline 2")
	)
	(footprint "Vault:CAPC0603X033N"
		(layer "B.Cu")
		(at 143.026105 104.798605 -90)
		(property "Reference" "C4"
			(at -3.4161 0.48 0)
			(unlocked yes)
			(layer "B.SilkS")
			(effects
				(font
					(face "Arial")
					(size 0.63 0.63)
					(thickness 0.254)
				)
				(justify mirror)
			)
		)
		(property "Value" "Murata_GRM0335C1E330JA01D"
			(at 11.84658 -8.56076 0)
			(unlocked yes)
			(layer "B.SilkS")
			(hide yes)
			(effects
				(font
					(face "Arial")
					(size 0.63 0.63)
					(thickness 0.254)
				)
				(justify mirror)
			)
		)
		(sheetname "SCH_SA45_DaughterCard")
		(sheetfile "SCH_SA45_DaughterCard.kicad_sch")
		(duplicate_pad_numbers_are_jumpers no)
		(fp_line
			(start -0.75 0.4)
			(end -0.75 -0.4)
			(stroke
				(width 0.1)
				(type solid)
			)
			(layer "B.CrtYd")
		)
		(fp_line
			(start 0.75 0.4)
			(end -0.75 0.4)
			(stroke
				(width 0.1)
				(type solid)
			)
			(layer "B.CrtYd")
		)
		(fp_line
			(start 0.75 0.4)
			(end 0.75 -0.4)
			(stroke
				(width 0.1)
				(type solid)
			)
			(layer "B.CrtYd")
		)
		(fp_line
			(start 0.75 -0.4)
			(end -0.75 -0.4)
			(stroke
				(width 0.1)
				(type solid)
			)
			(layer "B.CrtYd")
		)
		(fp_line
			(start -0.3 0.15)
			(end -0.3 -0.15)
			(stroke
				(width 0.05)
				(type solid)
			)
			(layer "B.Fab")
		)
		(fp_line
			(start 0.3 0.15)
			(end -0.3 0.15)
			(stroke
				(width 0.05)
				(type solid)
			)
			(layer "B.Fab")
		)
		(fp_line
			(start 0.3 0.15)
			(end 0.3 -0.15)
			(stroke
				(width 0.05)
				(type solid)
			)
			(layer "B.Fab")
		)
		(fp_line
			(start 0.3 -0.15)
			(end -0.3 -0.15)
			(stroke
				(width 0.05)
				(type solid)
			)
			(layer "B.Fab")
		)
		(fp_text_box "${REFERENCE}"
			(start -0.20757 1.14715)
			(end 0.20756 -1.14715)
			(margins 0 0 0 0)
			(angle 90)
			(layer "B.Fab")
			(effects
				(font
					(face "Arial")
					(size 0.315 0.315)
					(thickness 0.254)
				)
				(justify top mirror)
			)
			(border no)
			(stroke
				(width 0.1)
				(type default)
			)
			(knockout no)
		)
		(pad "1" smd rect
			(at -0.33 0 270)
			(size 0.46 0.42)
			(layers "B.Cu" "B.Mask" "B.Paste")
			(net "+3.3V")
			(solder_mask_margin 0.05)
			(solder_paste_margin 0)
		)
		(pad "2" smd rect
			(at 0.33 0 270)
			(size 0.46 0.42)
			(layers "B.Cu" "B.Mask" "B.Paste")
			(net "NetC4_2")
			(solder_mask_margin 0.05)
			(solder_paste_margin 0)
		)
	)
	(footprint "Vault:TH000V_300DIAx400_001mt_9774040243R"
		(locked yes)
		(layer "B.Cu")
		(at 148.601105 126.603605 180)
		(property "Reference" "J1"
			(at -0.00185 4.13071 0)
			(unlocked yes)
			(layer "B.SilkS")
			(effects
				(font
					(face "Arial")
					(size 0.63 0.63)
					(thickness 0.254)
				)
				(justify mirror)
			)
		)
		(property "Value" "Wurth_9774040243R"
			(at 9.66063 -4.57418 0)
			(unlocked yes)
			(layer "B.SilkS")
			(hide yes)
			(effects
				(font
					(face "Arial")
					(size 0.63 0.63)
					(thickness 0.254)
				)
				(justify mirror)
			)
		)
		(sheetname "SCH_SA45_DaughterCard")
		(sheetfile "SCH_SA45_DaughterCard.kicad_sch")
		(duplicate_pad_numbers_are_jumpers no)
		(fp_line
			(start 3.1 3.1)
			(end -3.1 3.1)
			(stroke
				(width 0.1)
				(type solid)
			)
			(layer "B.CrtYd")
		)
		(fp_line
			(start 3.1 -3.1)
			(end 3.1 3.1)
			(stroke
				(width 0.1)
				(type solid)
			)
			(layer "B.CrtYd")
		)
		(fp_line
			(start 3.1 -3.1)
			(end -3.1 -3.1)
			(stroke
				(width 0.1)
				(type solid)
			)
			(layer "B.CrtYd")
		)
		(fp_line
			(start -3.1 -3.1)
			(end -3.1 3.1)
			(stroke
				(width 0.1)
				(type solid)
			)
			(layer "B.CrtYd")
		)
		(fp_circle
			(center 0 0)
			(end 0 1.5)
			(stroke
				(width 0.1)
				(type solid)
			)
			(fill no)
			(layer "B.Fab")
		)
		(fp_text user "${REFERENCE}"
			(at -0.00235 0.166251 360)
			(unlocked yes)
			(layer "B.Fab")
			(effects
				(font
					(face "Arial")
					(size 0.8001 0.8001)
					(thickness 0.254)
				)
				(justify mirror)
			)
		)
		(pad "" np_thru_hole circle
			(at 0 0 180)
			(size 5.3 5.3)
			(drill 3)
			(layers "*.Cu" "*.Mask")
			(solder_mask_margin 0.2)
			(solder_paste_margin -2147.48364)
			(thermal_bridge_angle 90)
		)
	)
	(footprint "Vault:CAPC2013X140N"
		(layer "B.Cu")
		(at 151.476105 115.053605 180)
		(property "Reference" "C10"
			(at -2.95163 0.12656 0)
			(unlocked yes)
			(layer "B.SilkS")
			(effects
				(font
					(face "Arial")
					(size 0.63 0.63)
					(thickness 0.254)
				)
				(justify mirror)
			)
		)
		(property "Value" "Murata_GRM21BR61A226ME51L"
			(at 21.20959 3.13786 0)
			(unlocked yes)
			(layer "B.SilkS")
			(hide yes)
			(effects
				(font
					(face "Arial")
					(size 0.63 0.63)
					(thickness 0.254)
				)
				(justify mirror)
			)
		)
		(sheetname "SCH_SA45_DaughterCard")
		(sheetfile "SCH_SA45_DaughterCard.kicad_sch")
		(duplicate_pad_numbers_are_jumpers no)
		(fp_line
			(start 1.8 1.1)
			(end -1.8 1.1)
			(stroke
				(width 0.1)
				(type solid)
			)
			(layer "B.CrtYd")
		)
		(fp_line
			(start 1.8 -1.1)
			(end 1.8 1.1)
			(stroke
				(width 0.1)
				(type solid)
			)
			(layer "B.CrtYd")
		)
		(fp_line
			(start 1.8 -1.1)
			(end -1.8 -1.1)
			(stroke
				(width 0.1)
				(type solid)
			)
			(layer "B.CrtYd")
		)
		(fp_line
			(start -1.8 -1.1)
			(end -1.8 1.1)
			(stroke
				(width 0.1)
				(type solid)
			)
			(layer "B.CrtYd")
		)
		(fp_line
			(start 1 0.65)
			(end -1 0.65)
			(stroke
				(width 0.05)
				(type solid)
			)
			(layer "B.Fab")
		)
		(fp_line
			(start 1 -0.65)
			(end 1 0.65)
			(stroke
				(width 0.05)
				(type solid)
			)
			(layer "B.Fab")
		)
		(fp_line
			(start 1 -0.65)
			(end -1 -0.65)
			(stroke
				(width 0.05)
				(type solid)
			)
			(layer "B.Fab")
		)
		(fp_line
			(start -1 -0.65)
			(end -1 0.65)
			(stroke
				(width 0.05)
				(type solid)
			)
			(layer "B.Fab")
		)
		(fp_text_box "${REFERENCE}"
			(start 1.09004 0.20729)
			(end -1.09004 -0.20729)
			(margins 0 0 0 0)
			(angle -180)
			(layer "B.Fab")
			(effects
				(font
					(face "Arial")
					(size 0.315 0.315)
					(thickness 0.254)
				)
				(justify top mirror)
			)
			(border no)
			(stroke
				(width 0.1)
				(type default)
			)
			(knockout no)
		)
		(pad "1" smd rect
			(at -0.9 0 180)
			(size 1.3 1.65)
			(layers "B.Cu" "B.Mask" "B.Paste")
			(net "+3.3V")
			(solder_mask_margin 0.05)
			(solder_paste_margin 0)
		)
		(pad "2" smd rect
			(at 0.9 0 180)
			(size 1.3 1.65)
			(layers "B.Cu" "B.Mask" "B.Paste")
			(net "GND")
			(solder_mask_margin 0.05)
			(solder_paste_margin 0)
		)
	)
	(footprint "Vault:FID_1p0mm"
		(layer "B.Cu")
		(at 171.351105 128.153605 180)
		(property "Reference" "Designator7"
			(at 7.084135 3.019298 0)
			(unlocked yes)
			(layer "B.SilkS")
			(hide yes)
			(effects
				(font
					(size 1.524 1.524)
					(thickness 0.254)
				)
				(justify mirror)
			)
		)
		(property "Value" "Comment"
			(at 5.07844 0.707898 0)
			(unlocked yes)
			(layer "B.SilkS")
			(hide yes)
			(effects
				(font
					(size 1.524 1.524)
					(thickness 0.254)
				)
				(justify mirror)
			)
		)
		(sheetfile ".kicad_sch")
		(duplicate_pad_numbers_are_jumpers no)
		(fp_circle
			(center 0 0)
			(end 0 1)
			(stroke
				(width 0.1)
				(type solid)
			)
			(fill no)
			(layer "B.CrtYd")
		)
		(pad "1" smd circle
			(at 0 0 90)
			(size 1 1)
			(layers "B.Cu" "B.Mask" "B.Paste")
			(solder_mask_margin 0.5)
			(solder_paste_margin -6)
			(thermal_bridge_angle 90)
		)
		(zone
			(layer "B.Cu")
			(hatch edge 0.5)
			(connect_pads
				(clearance 0)
			)
			(min_thickness 0.25)
			(keepout
				(tracks not_allowed)
				(vias not_allowed)
				(pads allowed)
				(copperpour not_allowed)
				(footprints allowed)
			)
			(placement
				(enabled no)
				(sheetname "")
			)
			(fill
				(thermal_gap 0.5)
				(thermal_bridge_width 0.5)
				(island_removal_mode 0)
			)
			(polygon
				(pts
					(xy 171.64139 127.196665) (xy 171.822502 127.271684) (xy 171.985498 127.380595) (xy 172.124115 127.519212)
					(xy 172.233026 127.682208) (xy 172.308045 127.86332) (xy 172.34629 128.055588) (xy 172.34629 128.251622)
					(xy 172.308045 128.44389) (xy 172.233026 128.625002) (xy 172.124115 128.787998) (xy 171.985498 128.926615)
					(xy 171.822502 129.035526) (xy 171.64139 129.110545) (xy 171.449122 129.14879) (xy 171.253088 129.14879)
					(xy 171.06082 129.110545) (xy 170.879708 129.035526) (xy 170.716712 128.926615) (xy 170.578095 128.787998)
					(xy 170.469184 128.625002) (xy 170.394165 128.44389) (xy 170.35592 128.251622) (xy 170.35592 128.087779)
					(xy 170.851105 128.087779) (xy 170.851105 128.219431) (xy 170.88518 128.346598) (xy 170.951006 128.460612)
					(xy 171.044098 128.553704) (xy 171.158112 128.61953) (xy 171.285279 128.653605) (xy 171.416931 128.653605)
					(xy 171.544098 128.61953) (xy 171.658112 128.553704) (xy 171.751204 128.460612) (xy 171.81703 128.346598)
					(xy 171.851105 128.219431) (xy 171.851105 128.087779) (xy 171.81703 127.960612) (xy 171.751204 127.846598)
					(xy 171.658112 127.753506) (xy 171.544098 127.68768) (xy 171.416931 127.653605) (xy 171.285279 127.653605)
					(xy 171.158112 127.68768) (xy 171.044098 127.753506) (xy 170.951006 127.846598) (xy 170.88518 127.960612)
					(xy 170.851105 128.087779) (xy 170.35592 128.087779) (xy 170.35592 128.055588) (xy 170.394165 127.86332)
					(xy 170.469184 127.682208) (xy 170.578095 127.519212) (xy 170.716712 127.380595) (xy 170.879708 127.271684)
					(xy 171.06082 127.196665) (xy 171.253088 127.15842) (xy 171.449122 127.15842)
				)
			)
		)
	)
	(footprint "Vault:CAPC1005X055N"
		(layer "B.Cu")
		(at 151.576105 113.053605 180)
		(property "Reference" "C12"
			(at -2.85163 0.12655 0)
			(unlocked yes)
			(layer "B.SilkS")
			(effects
				(font
					(face "Arial")
					(size 0.63 0.63)
					(thickness 0.254)
				)
				(justify mirror)
			)
		)
		(property "Value" "Murata_GRM155R61H104KE14D"
			(at 25.338025 1.61026 0)
			(unlocked yes)
			(layer "B.SilkS")
			(hide yes)
			(effects
				(font
					(face "Arial")
					(size 0.63 0.63)
					(thickness 0.254)
				)
				(justify mirror)
			)
		)
		(sheetname "SCH_SA45_DaughterCard")
		(sheetfile "SCH_SA45_DaughterCard.kicad_sch")
		(duplicate_pad_numbers_are_jumpers no)
		(fp_line
			(start 0.95 0.5)
			(end -0.95 0.5)
			(stroke
				(width 0.1)
				(type solid)
			)
			(layer "B.CrtYd")
		)
		(fp_line
			(start 0.95 -0.5)
			(end 0.95 0.5)
			(stroke
				(width 0.1)
				(type solid)
			)
			(layer "B.CrtYd")
		)
		(fp_line
			(start 0.95 -0.5)
			(end -0.95 -0.5)
			(stroke
				(width 0.1)
				(type solid)
			)
			(layer "B.CrtYd")
		)
		(fp_line
			(start -0.95 -0.5)
			(end -0.95 0.5)
			(stroke
				(width 0.1)
				(type solid)
			)
			(layer "B.CrtYd")
		)
		(fp_line
			(start 0.5 0.25)
			(end -0.5 0.25)
			(stroke
				(width 0.05)
				(type solid)
			)
			(layer "B.Fab")
		)
		(fp_line
			(start 0.5 -0.25)
			(end 0.5 0.25)
			(stroke
				(width 0.05)
				(type solid)
			)
			(layer "B.Fab")
		)
		(fp_line
			(start 0.5 -0.25)
			(end -0.5 -0.25)
			(stroke
				(width 0.05)
				(type solid)
			)
			(layer "B.Fab")
		)
		(fp_line
			(start -0.5 -0.25)
			(end -0.5 0.25)
			(stroke
				(width 0.05)
				(type solid)
			)
			(layer "B.Fab")
		)
		(fp_text_box "${REFERENCE}"
			(start 1.09004 0.20727)
			(end -1.09004 -0.20726)
			(margins 0 0 0 0)
			(angle -180)
			(layer "B.Fab")
			(effects
				(font
					(face "Arial")
					(size 0.315 0.315)
					(thickness 0.254)
				)
				(justify top mirror)
			)
			(border no)
			(stroke
				(width 0.1)
				(type default)
			)
			(knockout no)
		)
		(pad "1" smd rect
			(at -0.46 0 180)
			(size 0.6 0.62)
			(layers "B.Cu" "B.Mask" "B.Paste")
			(net "+3.3V")
			(solder_mask_margin 0.05)
			(solder_paste_margin 0)
		)
		(pad "2" smd rect
			(at 0.46 0 180)
			(size 0.6 0.62)
			(layers "B.Cu" "B.Mask" "B.Paste")
			(net "GND")
			(solder_mask_margin 0.05)
			(solder_paste_margin 0)
		)
	)
	(footprint "FAB_SA45_DaughterCard:DiodesInc_AP63356QZV-7"
		(layer "B.Cu")
		(at 145.326105 107.378605)
		(property "Reference" "U3"
			(at -2.450005 1.84429 0)
			(unlocked yes)
			(layer "B.SilkS")
			(effects
				(font
					(face "Arial")
					(size 0.63 0.63)
					(thickness 0.254)
				)
				(justify mirror)
			)
		)
		(property "Value" "DiodesInc_AP63356QZV-7"
			(at 6.94796 31.32414 0)
			(unlocked yes)
			(layer "B.SilkS")
			(hide yes)
			(effects
				(font
					(face "Arial")
					(size 0.63 0.63)
					(thickness 0.254)
				)
				(justify mirror)
			)
		)
		(sheetname "SCH_SA45_DaughterCard")
		(sheetfile "SCH_SA45_DaughterCard.kicad_sch")
		(duplicate_pad_numbers_are_jumpers no)
		(fp_rect
			(start -1.19996 0.22787)
			(end -0.49996 -1.17501)
			(stroke
				(width 0)
				(type default)
			)
			(fill yes)
			(layer "B.Mask")
		)
		(fp_rect
			(start 0.49996 0.22499)
			(end 1.19996 -1.17501)
			(stroke
				(width 0)
				(type default)
			)
			(fill yes)
			(layer "B.Mask")
		)
		(fp_line
			(start -1.4 -1.33125)
			(end 1.4 -1.33125)
			(stroke
				(width 0.1)
				(type solid)
			)
			(layer "B.CrtYd")
		)
		(fp_line
			(start -1.4 0.66874)
			(end -1.4 -1.33125)
			(stroke
				(width 0.1)
				(type solid)
			)
			(layer "B.CrtYd")
		)
		(fp_line
			(start -1.4 2.26875)
			(end -1.4 0.66874)
			(stroke
				(width 0.1)
				(type solid)
			)
			(layer "B.CrtYd")
		)
		(fp_line
			(start -1.4 2.26875)
			(end 1.3 2.26875)
			(stroke
				(width 0.1)
				(type solid)
			)
			(layer "B.CrtYd")
		)
		(fp_line
			(start 1.3 2.26875)
			(end 1.4 2.26875)
			(stroke
				(width 0.1)
				(type solid)
			)
			(layer "B.CrtYd")
		)
		(fp_line
			(start 1.4 2.26875)
			(end 1.4 -1.33125)
			(stroke
				(width 0.1)
				(type solid)
			)
			(layer "B.CrtYd")
		)
		(fp_text user "${REFERENCE}"
			(at -0.000005 -0.06197 360)
			(unlocked yes)
			(layer "B.Fab")
			(effects
				(font
					(face "Arial")
					(size 0.63 0.63)
					(thickness 0.254)
				)
				(justify mirror)
			)
		)
		(fp_text user ""
			(at 0.367795 0.63442 180)
			(unlocked yes)
			(layer "B.Fab")
			(effects
				(font
					(face "Arial")
					(size 0.63 0.63)
					(thickness 0.254)
				)
				(justify mirror)
			)
		)
		(pad "1" smd rect
			(at -0.75 0.975)
			(size 0.8 1.45)
			(layers "B.Cu" "B.Mask" "B.Paste")
			(net "+5V")
			(solder_mask_margin 0.05)
			(solder_paste_margin 0)
		)
		(pad "2" smd rect
			(at -0.85 -0.075)
			(size 0.6 0.3)
			(layers "B.Cu" "B.Mask" "B.Paste")
			(net "+5V")
			(solder_mask_margin 0.05)
			(solder_paste_margin 0)
		)
		(pad "3" smd rect
			(at -0.85 -0.525)
			(size 0.6 0.3)
			(layers "B.Cu" "B.Mask" "B.Paste")
			(net "NetC4_2")
			(solder_mask_margin 0.05)
			(solder_paste_margin 0)
		)
		(pad "4" smd rect
			(at -0.85 -0.975)
			(size 0.6 0.3)
			(layers "B.Cu" "B.Mask" "B.Paste")
			(net "NetR5_1")
			(solder_mask_margin 0.05)
			(solder_paste_margin 0)
		)
		(pad "5" smd rect
			(at 0.85 -0.975)
			(size 0.6 0.3)
			(layers "B.Cu" "B.Mask" "B.Paste")
			(solder_mask_margin 0.05)
			(solder_paste_margin 0)
		)
		(pad "6" smd rect
			(at 0.85 -0.525)
			(size 0.6 0.3)
			(layers "B.Cu" "B.Mask" "B.Paste")
			(net "NetC3_1")
			(solder_mask_margin 0.05)
			(solder_paste_margin 0)
		)
		(pad "7" smd rect
			(at 0.85 -0.075)
			(size 0.6 0.3)
			(layers "B.Cu" "B.Mask" "B.Paste")
			(net "SW")
			(solder_mask_margin 0.05)
			(solder_paste_margin 0)
		)
		(pad "8" smd rect
			(at 0.75 0.975)
			(size 0.8 1.45)
			(layers "B.Cu" "B.Mask" "B.Paste")
			(net "GND")
			(solder_mask_margin 0.05)
			(solder_paste_margin 0)
		)
		(pad "9" smd rect
			(at 0 1.1125)
			(size 0.3 1.725)
			(layers "B.Cu" "B.Mask" "B.Paste")
			(net "SW")
			(solder_mask_margin 0.05)
			(solder_paste_margin 0)
		)
	)
	(footprint "Vault:CAPC1005X055N"
		(layer "B.Cu")
		(at 146.841105 104.168605)
		(property "Reference" "C3"
			(at 0.4475 -1.15335 0)
			(unlocked yes)
			(layer "B.SilkS")
			(effects
				(font
					(face "Arial")
					(size 0.63 0.63)
					(thickness 0.254)
				)
				(justify mirror)
			)
		)
		(property "Value" "Murata_GRM155R61H104KE14D"
			(at -0.824235 18.44158 0)
			(unlocked yes)
			(layer "B.SilkS")
			(hide yes)
			(effects
				(font
					(face "Arial")
					(size 0.63 0.63)
					(thickness 0.254)
				)
				(justify mirror)
			)
		)
		(sheetname "SCH_SA45_DaughterCard")
		(sheetfile "SCH_SA45_DaughterCard.kicad_sch")
		(duplicate_pad_numbers_are_jumpers no)
		(fp_line
			(start -0.95 -0.5)
			(end 0.95 -0.5)
			(stroke
				(width 0.1)
				(type solid)
			)
			(layer "B.CrtYd")
		)
		(fp_line
			(start -0.95 0.5)
			(end -0.95 -0.5)
			(stroke
				(width 0.1)
				(type solid)
			)
			(layer "B.CrtYd")
		)
		(fp_line
			(start -0.95 0.5)
			(end 0.95 0.5)
			(stroke
				(width 0.1)
				(type solid)
			)
			(layer "B.CrtYd")
		)
		(fp_line
			(start 0.95 0.5)
			(end 0.95 -0.5)
			(stroke
				(width 0.1)
				(type solid)
			)
			(layer "B.CrtYd")
		)
		(fp_line
			(start -0.5 -0.25)
			(end 0.5 -0.25)
			(stroke
				(width 0.05)
				(type solid)
			)
			(layer "B.Fab")
		)
		(fp_line
			(start -0.5 0.25)
			(end -0.5 -0.25)
			(stroke
				(width 0.05)
				(type solid)
			)
			(layer "B.Fab")
		)
		(fp_line
			(start -0.5 0.25)
			(end 0.5 0.25)
			(stroke
				(width 0.05)
				(type solid)
			)
			(layer "B.Fab")
		)
		(fp_line
			(start 0.5 0.25)
			(end 0.5 -0.25)
			(stroke
				(width 0.05)
				(type solid)
			)
			(layer "B.Fab")
		)
		(fp_text_box "${REFERENCE}"
			(start 1.14717 0.20757)
			(end -1.14713 -0.20756)
			(margins 0 0 0 0)
			(angle 180)
			(layer "B.Fab")
			(effects
				(font
					(face "Arial")
					(size 0.315 0.315)
					(thickness 0.254)
				)
				(justify top mirror)
			)
			(border no)
			(stroke
				(width 0.1)
				(type default)
			)
			(knockout no)
		)
		(pad "1" smd rect
			(at -0.46 0)
			(size 0.6 0.62)
			(layers "B.Cu" "B.Mask" "B.Paste")
			(net "NetC3_1")
			(solder_mask_margin 0.05)
			(solder_paste_margin 0)
		)
		(pad "2" smd rect
			(at 0.46 0)
			(size 0.6 0.62)
			(layers "B.Cu" "B.Mask" "B.Paste")
			(net "SW")
			(solder_mask_margin 0.05)
			(solder_paste_margin 0)
		)
	)
)
